FILE_TYPE=LIBRARY_PARTS;
primitive '47KR2F-GP_RCL_GP';
  pin
    '1':
      PIN_NUMBER='(1)';
      PIN_TYPE='ANALOG';
      NO_LOAD_CHECK='Both';
      NO_IO_CHECK='Both';
      NO_ASSERT_CHECK='TRUE';
      NO_DIR_CHECK='TRUE';
      ALLOW_CONNECT='TRUE';
    '2':
      PIN_NUMBER='(2)';
      PIN_TYPE='ANALOG';
      NO_LOAD_CHECK='Both';
      NO_IO_CHECK='Both';
      NO_ASSERT_CHECK='TRUE';
      NO_DIR_CHECK='TRUE';
      ALLOW_CONNECT='TRUE';
  end_pin;
  body
    PART_NAME='47KR2F-GP';
    BODY_NAME='47KR2F-GP';
    PHYS_DES_PREFIX='R';
    CLASS='DISCRETE';
  end_body;
end_primitive;

END.
